FILE_TYPE = MULTI_PHYS_TABLE;
PART 'ADM1278'
{=============================================================================================================================================================================}
:PACK_TYPE | MATERIAL | PART_NUMBER     = EnvComp | PART_NUMBER  | JEDEC_TYPE        | DESCRIPTION                            | CLASS | COMPONENT_TYPE | HEIGHT     | LPID   | SPEED_URL | Status |RPL| AML | Bus_Unit | Days ;
{=============================================================================================================================================================================}
'SM'       | 'IC'     | 'G99251-001'(!) = 'YES;YES;YES;UNK;ok;VLD' | 'G99251-001' | 'QFN32_20_5MB'    | 'IC,LIN,CONT,20,LFCSP,ADM1278-1,PSP'   | 'IC'  | 'LCC'          | '0.031 IN' | '2397' | 'http://speed.intel.com:8081/speed/module/pdm/item/pdm_item_detail_direct.asp?item_cde=G99251-001&item_rev=01&url_param=unused' | 'Design' | 'NO' | '1' | 'SMO_IC' | '???' 
'SM'       | 'EMPTY'  | 'G99251-001'(!) = 'YES;YES;YES;UNK;ok;VLD' | 'G99251-001' | 'QFN32_20_5MB'    | 'IC,LIN,CONT,20,LFCSP,ADM1278-1,PSP'   | 'IO'  | 'LCC'          | '0.031 IN' | '2397' | 'http://speed.intel.com:8081/speed/module/pdm/item/pdm_item_detail_direct.asp?item_cde=G99251-001&item_rev=01&url_param=unused' | 'Design' | 'NO' | '1' | 'SMO_IC' | '???' 
END_PART
END.
